# BASEBOARD_FAB2 (Tioga Pass) — schematic netlist excerpt (pin names and nets, part order shuffled) for the footprints in the layout excerpt that follows; sources: Cadence DE-HDL packaged netlist, KiCad conversion of Wiwynn_Tioga_Pass_MB.brd

R6P40  RES  100.0K 1% EMPTY  pkg 0402  page 213 : A = P3V3_STBY ; B = VR_PVCCIO_CPU1_EN
C4R1  CAPP  470UF 2.5V 20% ALUM  pkg 3018  page 194 : A = PVCCMCP_CPU0 ; B = GND
C5G75  CAP_A  22.0UF 4V 20% X6S  pkg 0603V  page 242 : A = PVDDQ_DEF ; B = GND

(kicad_pcb
	(version 20260206)
	(generator "pcbnew")
	(generator_version "10.0")
	(general
		(thickness 1.6)
		(legacy_teardrops no)
	)
	(paper "A4")
	(title_block
		(title "Wiwynn_Tioga_Pass_MB.brd")
		(comment 1 "Tioga Pass / footprints 3550-3552 of 4770")
	)
	(layers
		(0 "F.Cu" signal "TOP")
		(4 "In1.Cu" signal "L2GND")
		(6 "In2.Cu" signal "L3")
		(8 "In3.Cu" signal "L4GND")
		(10 "In4.Cu" signal "L5")
		(12 "In5.Cu" signal "L6GND")
		(14 "In6.Cu" signal "L7VCC")
		(16 "In7.Cu" signal "L8VCC")
		(18 "In8.Cu" signal "L9GND")
		(20 "In9.Cu" signal "L10")
		(22 "In10.Cu" signal "L11GND")
		(24 "In11.Cu" signal "L12")
		(26 "In12.Cu" signal "L13GND")
		(2 "B.Cu" signal "BOTTOM")
		(9 "F.Adhes" user "F.Adhesive")
		(11 "B.Adhes" user "B.Adhesive")
		(13 "F.Paste" user "Package Geometry/Pastemask Top")
		(15 "B.Paste" user "Package Geometry/Pastemask Bottom")
		(5 "F.SilkS" user "Ref Des/Silkscreen Top")
		(7 "B.SilkS" user "Ref Des/Silkscreen Bottom")
		(1 "F.Mask" user "Board Geometry/Soldermask Top")
		(3 "B.Mask" user "Board Geometry/Soldermask Bottom")
		(17 "Dwgs.User" user "User.Drawings")
		(19 "Cmts.User" user "User.Comments")
		(21 "Eco1.User" user "User.Eco1")
		(23 "Eco2.User" user "User.Eco2")
		(25 "Edge.Cuts" user "Board Geometry/Outline")
		(27 "Margin" user)
		(31 "F.CrtYd" user "Package Geometry/Place Bound Top")
		(29 "B.CrtYd" user "Package Geometry/Place Bound Bottom")
		(35 "F.Fab" user "Ref Des/Assembly Top")
		(33 "B.Fab" user "Ref Des/Assembly Bottom")
	)
	(footprint ""
		(layer "B.Cu")
		(at 272.861532 -140.208 90)
		(property "Reference" "C5G75"
			(at -1.14681 0.76708 180)
			(unlocked yes)
			(layer "B.SilkS")
			(effects
				(font
					(size 0.7874 0.5842)
					(thickness 0.1524)
				)
				(justify mirror)
			)
		)
		(property "Value" ""
			(at 0 0 90)
			(layer "B.Fab")
			(effects
				(font
					(size 1.27 1.27)
				)
				(justify mirror)
			)
		)
		(duplicate_pad_numbers_are_jumpers no)
		(fp_rect
			(start -0.4953 -0.2032)
			(end 0.4953 1.6002)
			(stroke
				(width 0)
				(type default)
			)
			(fill no)
			(layer "B.CrtYd")
		)
		(fp_line
			(start 0.4953 -0.2032)
			(end -0.4953 -0.2032)
			(stroke
				(width 0.1)
				(type default)
			)
			(layer "B.Fab")
		)
		(fp_line
			(start -0.4953 -0.2032)
			(end -0.4953 1.6002)
			(stroke
				(width 0.1)
				(type default)
			)
			(layer "B.Fab")
		)
		(fp_line
			(start 0.4953 1.6002)
			(end 0.4953 -0.2032)
			(stroke
				(width 0.1)
				(type default)
			)
			(layer "B.Fab")
		)
		(fp_line
			(start -0.4953 1.6002)
			(end 0.4953 1.6002)
			(stroke
				(width 0.1)
				(type default)
			)
			(layer "B.Fab")
		)
		(pad "1" smd rect
			(at 0 0 270)
			(size 0.762 0.889)
			(layers "B.Cu" "B.Mask" "B.Paste")
			(net "PVDDQ_DEF")
		)
		(pad "2" smd rect
			(at 0 1.397 270)
			(size 0.762 0.889)
			(layers "B.Cu" "B.Mask" "B.Paste")
			(net "GND")
		)
		(zone
			(layer "B.Cu")
			(hatch none 0.5)
			(connect_pads
				(clearance 0)
			)
			(min_thickness 0.25)
			(keepout
				(tracks not_allowed)
				(vias allowed)
				(pads allowed)
				(copperpour not_allowed)
				(footprints allowed)
			)
			(placement
				(enabled no)
				(sheetname "")
			)
			(fill
				(thermal_gap 0.5)
				(thermal_bridge_width 0.5)
				(island_removal_mode 0)
			)
			(polygon
				(pts
					(xy 273.306032 -139.827) (xy 273.814032 -139.827) (xy 273.814032 -140.589) (xy 273.306032 -140.589)
				)
			)
		)
	)
	(footprint ""
		(layer "B.Cu")
		(at 164.973 -67.2592 90)
		(property "Reference" "R6P40"
			(at 0 0 90)
			(layer "B.SilkS")
			(hide yes)
			(effects
				(font
					(size 1.27 1.27)
				)
				(justify mirror)
			)
		)
		(property "Value" ""
			(at 0 0 90)
			(layer "B.Fab")
			(effects
				(font
					(size 1.27 1.27)
				)
				(justify mirror)
			)
		)
		(duplicate_pad_numbers_are_jumpers no)
		(fp_poly
			(pts
				(xy 0.2794 -0.1016) (xy -0.2794 -0.1016) (xy -0.2794 0.9906) (xy 0.2794 0.9906)
			)
			(stroke
				(width 0)
				(type default)
			)
			(fill no)
			(layer "B.CrtYd")
		)
		(fp_line
			(start 0.2794 -0.1016)
			(end 0.2794 0.9906)
			(stroke
				(width 0.1)
				(type default)
			)
			(layer "B.Fab")
		)
		(fp_line
			(start -0.2794 -0.1016)
			(end 0.2794 -0.1016)
			(stroke
				(width 0.1)
				(type default)
			)
			(layer "B.Fab")
		)
		(fp_line
			(start 0.2794 0.9906)
			(end -0.2794 0.9906)
			(stroke
				(width 0.1)
				(type default)
			)
			(layer "B.Fab")
		)
		(fp_line
			(start -0.2794 0.9906)
			(end -0.2794 -0.1016)
			(stroke
				(width 0.1)
				(type default)
			)
			(layer "B.Fab")
		)
		(pad "1" smd rect
			(at 0 0 270)
			(size 0.508 0.508)
			(layers "B.Cu" "B.Mask" "B.Paste")
			(net "P3V3_STBY")
		)
		(pad "2" smd rect
			(at 0 0.889 270)
			(size 0.508 0.508)
			(layers "B.Cu" "B.Mask" "B.Paste")
			(net "VR_PVCCIO_CPU1_EN")
		)
		(zone
			(layer "B.Cu")
			(hatch none 0.5)
			(connect_pads
				(clearance 0)
			)
			(min_thickness 0.25)
			(keepout
				(tracks allowed)
				(vias not_allowed)
				(pads allowed)
				(copperpour not_allowed)
				(footprints allowed)
			)
			(placement
				(enabled no)
				(sheetname "")
			)
			(fill
				(thermal_gap 0.5)
				(thermal_bridge_width 0.5)
				(island_removal_mode 0)
			)
			(polygon
				(pts
					(xy 165.227 -67.5132) (xy 165.227 -67.0052) (xy 165.608 -67.0052) (xy 165.608 -67.5132)
				)
			)
		)
		(zone
			(layer "B.Cu")
			(hatch none 0.5)
			(connect_pads
				(clearance 0)
			)
			(min_thickness 0.25)
			(keepout
				(tracks not_allowed)
				(vias allowed)
				(pads allowed)
				(copperpour not_allowed)
				(footprints allowed)
			)
			(placement
				(enabled no)
				(sheetname "")
			)
			(fill
				(thermal_gap 0.5)
				(thermal_bridge_width 0.5)
				(island_removal_mode 0)
			)
			(polygon
				(pts
					(xy 165.608 -67.5132) (xy 165.608 -67.0052) (xy 165.227 -67.0052) (xy 165.227 -67.5132)
				)
			)
		)
	)
	(footprint ""
		(layer "B.Cu")
		(at 342.8238 -46.6598 90)
		(property "Reference" "C4R1"
			(at 3.07467 3.429 180)
			(unlocked yes)
			(layer "B.SilkS")
			(effects
				(font
					(size 0.7874 0.5842)
					(thickness 0.1524)
				)
				(justify mirror)
			)
		)
		(property "Value" ""
			(at 0 0 90)
			(layer "B.Fab")
			(effects
				(font
					(size 1.27 1.27)
				)
				(justify mirror)
			)
		)
		(duplicate_pad_numbers_are_jumpers no)
		(fp_line
			(start 2.563114 -1.616456)
			(end 2.563114 1.633728)
			(stroke
				(width 0.1524)
				(type default)
			)
			(layer "B.SilkS")
		)
		(fp_line
			(start 1.6002 -1.616456)
			(end 2.563114 -1.616456)
			(stroke
				(width 0.1524)
				(type default)
			)
			(layer "B.SilkS")
		)
		(fp_line
			(start -1.6002 -1.616456)
			(end -2.504948 -1.616456)
			(stroke
				(width 0.1524)
				(type default)
			)
			(layer "B.SilkS")
		)
		(fp_line
			(start -2.504948 -1.616456)
			(end -2.504948 1.633728)
			(stroke
				(width 0.1524)
				(type default)
			)
			(layer "B.SilkS")
		)
		(fp_line
			(start 2.563114 1.633728)
			(end 1.6002 1.633728)
			(stroke
				(width 0.1524)
				(type default)
			)
			(layer "B.SilkS")
		)
		(fp_line
			(start -2.504948 1.633728)
			(end -1.6002 1.633728)
			(stroke
				(width 0.1524)
				(type default)
			)
			(layer "B.SilkS")
		)
		(fp_line
			(start 2.286 7.366)
			(end 2.286 1.632712)
			(stroke
				(width 0.1524)
				(type default)
			)
			(layer "B.SilkS")
		)
		(fp_line
			(start 2.286 7.366)
			(end 1.60147 7.366)
			(stroke
				(width 0.1524)
				(type default)
			)
			(layer "B.SilkS")
		)
		(fp_line
			(start -2.286 7.366)
			(end -2.286 1.63195)
			(stroke
				(width 0.1524)
				(type default)
			)
			(layer "B.SilkS")
		)
		(fp_line
			(start -2.286 7.366)
			(end -1.600708 7.366)
			(stroke
				(width 0.1524)
				(type default)
			)
			(layer "B.SilkS")
		)
		(fp_rect
			(start 2.286 7.366)
			(end -2.286 -0.254)
			(stroke
				(width 0)
				(type default)
			)
			(fill no)
			(layer "B.CrtYd")
		)
		(fp_line
			(start 2.286 -0.254)
			(end -2.286 -0.254)
			(stroke
				(width 0.1)
				(type default)
			)
			(layer "B.Fab")
		)
		(fp_line
			(start -2.286 -0.254)
			(end -2.286 7.366)
			(stroke
				(width 0.1)
				(type default)
			)
			(layer "B.Fab")
		)
		(fp_line
			(start 2.286 7.366)
			(end 2.286 -0.254)
			(stroke
				(width 0.1)
				(type default)
			)
			(layer "B.Fab")
		)
		(fp_line
			(start -2.286 7.366)
			(end 2.286 7.366)
			(stroke
				(width 0.1)
				(type default)
			)
			(layer "B.Fab")
		)
		(pad "1" smd rect
			(at 0 0 270)
			(size 2.54 3.048)
			(layers "B.Cu" "B.Mask" "B.Paste")
			(net "PVCCMCP_CPU0")
		)
		(pad "2" smd rect
			(at 0 7.112 270)
			(size 2.54 3.048)
			(layers "B.Cu" "B.Mask" "B.Paste")
			(net "GND")
		)
	)
)
